(kicad_pcb
	(version 20241229)
	(generator "pcbnew")
	(generator_version "9.0")
	(general
		(thickness 1.61)
		(legacy_teardrops no)
	)
	(paper "A3")
	(title_block
		(title "SO-DIMM DDR5 Tester")
		(date "2025-11-26")
		(rev "1.3.0")
		(comment 9 "footprints 251-256 of 627")
	)
	(layers
		(0 "F.Cu" signal)
		(4 "In1.Cu" power)
		(6 "In2.Cu" mixed)
		(8 "In3.Cu" power)
		(10 "In4.Cu" mixed)
		(12 "In5.Cu" power)
		(14 "In6.Cu" mixed)
		(16 "In7.Cu" power)
		(18 "In8.Cu" power)
		(20 "In9.Cu" mixed)
		(22 "In10.Cu" power)
		(2 "B.Cu" signal)
		(9 "F.Adhes" user "F.Adhesive")
		(11 "B.Adhes" user "B.Adhesive")
		(13 "F.Paste" user)
		(15 "B.Paste" user)
		(5 "F.SilkS" user "F.Silkscreen")
		(7 "B.SilkS" user "B.Silkscreen")
		(1 "F.Mask" user)
		(3 "B.Mask" user)
		(17 "Dwgs.User" user "User.Drawings")
		(19 "Cmts.User" user "User.Comments")
		(21 "Eco1.User" user "User.Eco1")
		(23 "Eco2.User" user "User.Eco2")
		(25 "Edge.Cuts" user)
		(27 "Margin" user)
		(31 "F.CrtYd" user "F.Courtyard")
		(29 "B.CrtYd" user "B.Courtyard")
		(35 "F.Fab" user)
		(33 "B.Fab" user)
	)
	(footprint "antmicro-footprints:C_0402_1005Metric"
		(layer "F.Cu")
		(at 105.175001 147.9005)
		(descr "Capacitor SMD 0402")
		(tags "capacitor SMD 0402")
		(property "Reference" "C6"
			(at 0 -0.699 0)
			(layer "F.SilkS")
			(hide yes)
			(effects
				(font
					(size 0.7 0.7)
					(thickness 0.15)
				)
				(justify left bottom)
			)
		)
		(property "Value" "C_100n_0402"
			(at -1.022927 2.155213 0)
			(layer "F.Fab")
			(effects
				(font
					(size 0.7 0.7)
					(thickness 0.15)
				)
				(justify left bottom)
			)
		)
		(property "Datasheet" "https://www.murata.com/products/productdetail?partno=GRM155R61H104KE14%23"
			(at 0 0 0)
			(layer "F.Fab")
			(hide yes)
			(effects
				(font
					(size 1.27 1.27)
					(thickness 0.15)
				)
			)
		)
		(property "Author" "Antmicro"
			(at 0 0 0)
			(layer "F.Fab")
			(hide yes)
			(effects
				(font
					(size 1 1)
					(thickness 0.15)
				)
			)
		)
		(property "Dielectric" "X5R"
			(at 0 0 0)
			(layer "F.Fab")
			(hide yes)
			(effects
				(font
					(size 1 1)
					(thickness 0.15)
				)
			)
		)
		(property "License" "Apache-2.0"
			(at 0 0 0)
			(layer "F.Fab")
			(hide yes)
			(effects
				(font
					(size 1 1)
					(thickness 0.15)
				)
			)
		)
		(property "MPN" "GRM155R61H104KE14D"
			(at 0 0 0)
			(layer "F.Fab")
			(hide yes)
			(effects
				(font
					(size 1 1)
					(thickness 0.15)
				)
			)
		)
		(property "Manufacturer" "Murata"
			(at 0 0 0)
			(layer "F.Fab")
			(hide yes)
			(effects
				(font
					(size 1 1)
					(thickness 0.15)
				)
			)
		)
		(property "Val" "100n"
			(at 0 0 0)
			(layer "F.Fab")
			(hide yes)
			(effects
				(font
					(size 1 1)
					(thickness 0.15)
				)
			)
		)
		(property "Voltage" "50V"
			(at 0 0 0)
			(layer "F.Fab")
			(hide yes)
			(effects
				(font
					(size 1 1)
					(thickness 0.15)
				)
			)
		)
		(sheetname "/DDR5 SODIMM/")
		(sheetfile "ddr5-sodimm.kicad_sch")
		(attr smd)
		(fp_rect
			(start -0.9659 -0.481258)
			(end 0.9649 0.458742)
			(stroke
				(width 0.05)
				(type solid)
			)
			(fill no)
			(layer "F.CrtYd")
		)
		(fp_line
			(start -0.499 -0.25)
			(end 0.499 -0.25)
			(stroke
				(width 0.15)
				(type solid)
			)
			(layer "F.Fab")
		)
		(fp_line
			(start -0.499 0.248)
			(end -0.499 -0.25)
			(stroke
				(width 0.15)
				(type solid)
			)
			(layer "F.Fab")
		)
		(fp_line
			(start 0.499 -0.25)
			(end 0.499 0.248)
			(stroke
				(width 0.15)
				(type solid)
			)
			(layer "F.Fab")
		)
		(fp_line
			(start 0.499 0.248)
			(end -0.499 0.248)
			(stroke
				(width 0.15)
				(type solid)
			)
			(layer "F.Fab")
		)
		(pad "1" smd roundrect
			(at -0.484 0)
			(size 0.59 0.64)
			(layers "F.Cu" "F.Mask" "F.Paste")
			(roundrect_rratio 0.25)
			(net 1 "GND")
			(pintype "passive")
		)
		(pad "2" smd roundrect
			(at 0.484 0)
			(size 0.59 0.64)
			(layers "F.Cu" "F.Mask" "F.Paste")
			(roundrect_rratio 0.25)
			(net 201 "+5V")
			(pintype "passive")
		)
	)
	(footprint "antmicro-footprints:TP_1206_SMD_RCW-0C"
		(layer "F.Cu")
		(at 204.8 190 90)
		(property "Reference" "TP20"
			(at -2.29 -1.4 90)
			(layer "F.SilkS")
			(hide yes)
			(effects
				(font
					(size 0.7 0.7)
					(thickness 0.15)
				)
				(justify left bottom)
			)
		)
		(property "Value" "TP_1206_SMD_RCW-0C"
			(at -4.68 2.25 90)
			(layer "F.Fab")
			(effects
				(font
					(size 0.7 0.7)
					(thickness 0.15)
				)
				(justify left bottom)
			)
		)
		(property "Datasheet" "https://www.te.com/commerce/DocumentDelivery/DDEController?Action=srchrtrv&DocNm=1773266&DocType=DS&DocLang=English"
			(at 0 0 90)
			(layer "F.Fab")
			(hide yes)
			(effects
				(font
					(size 1.27 1.27)
					(thickness 0.15)
				)
			)
		)
		(property "Author" "Antmicro"
			(at 394.8 -14.8 0)
			(layer "F.Fab")
			(hide yes)
			(effects
				(font
					(size 1 1)
					(thickness 0.15)
				)
			)
		)
		(property "License" "Apache-2.0"
			(at 394.8 -14.8 0)
			(layer "F.Fab")
			(hide yes)
			(effects
				(font
					(size 1 1)
					(thickness 0.15)
				)
			)
		)
		(property "MPN" "RCW-0C"
			(at 394.8 -14.8 0)
			(layer "F.Fab")
			(hide yes)
			(effects
				(font
					(size 1 1)
					(thickness 0.15)
				)
			)
		)
		(property "Manufacturer" "TE Connectivity"
			(at 394.8 -14.8 0)
			(layer "F.Fab")
			(hide yes)
			(effects
				(font
					(size 1 1)
					(thickness 0.15)
				)
			)
		)
		(sheetname "/Supply/")
		(sheetfile "supply.kicad_sch")
		(attr smd)
		(fp_line
			(start 1.78 -0.981)
			(end 1.281 -0.981)
			(stroke
				(width 0.15)
				(type solid)
			)
			(layer "F.SilkS")
		)
		(fp_line
			(start 1.78 -0.981)
			(end 1.78 -0.479)
			(stroke
				(width 0.15)
				(type solid)
			)
			(layer "F.SilkS")
		)
		(fp_line
			(start -1.779 -0.981)
			(end -1.279 -0.981)
			(stroke
				(width 0.15)
				(type solid)
			)
			(layer "F.SilkS")
		)
		(fp_line
			(start -1.779 -0.981)
			(end -1.779 -0.479)
			(stroke
				(width 0.15)
				(type solid)
			)
			(layer "F.SilkS")
		)
		(fp_line
			(start -1.779 0.482)
			(end -1.779 0.98)
			(stroke
				(width 0.15)
				(type solid)
			)
			(layer "F.SilkS")
		)
		(fp_line
			(start -1.779 0.98)
			(end -1.279 0.98)
			(stroke
				(width 0.15)
				(type solid)
			)
			(layer "F.SilkS")
		)
		(fp_line
			(start 1.78 0.982)
			(end 1.78 0.482)
			(stroke
				(width 0.15)
				(type solid)
			)
			(layer "F.SilkS")
		)
		(fp_line
			(start 1.78 0.982)
			(end 1.281 0.982)
			(stroke
				(width 0.15)
				(type solid)
			)
			(layer "F.SilkS")
		)
		(fp_rect
			(start -2.101 -1.314)
			(end 2.1 1.312)
			(stroke
				(width 0.05)
				(type solid)
			)
			(fill no)
			(layer "F.CrtYd")
		)
		(fp_rect
			(start -1.601 -0.814)
			(end 1.6 0.812)
			(stroke
				(width 0.15)
				(type solid)
			)
			(fill no)
			(layer "F.Fab")
		)
		(pad "1" smd rect
			(at 0 0 90)
			(size 3.4 1.8)
			(layers "F.Cu" "F.Mask" "F.Paste")
			(net 1 "GND")
			(pinfunction "1")
			(pintype "passive")
		)
	)
	(footprint "antmicro-footprints:USON-10_2.5x1mm_P0.5mm"
		(layer "F.Cu")
		(at 84.8 172.95)
		(descr "USON-10 2.5x1mm_ Pitch 0.5mm")
		(tags "USON-10 2.5x1mm Pitch 0.5mm")
		(property "Reference" "U12"
			(at 0.018 -1.7 0)
			(layer "F.SilkS")
			(hide yes)
			(effects
				(font
					(size 0.7 0.7)
					(thickness 0.15)
				)
				(justify left bottom)
			)
		)
		(property "Value" "TPD4E05U06QDQARQ1"
			(at 0.018 2.499 0)
			(layer "F.Fab")
			(effects
				(font
					(size 0.7 0.7)
					(thickness 0.15)
				)
				(justify left bottom)
			)
		)
		(property "Datasheet" "https://www.ti.com/lit/ds/symlink/tpd4e05u06-q1.pdf?HQS=dis-mous-null-mousermode-dsf-pf-null-wwe&ts=1663591265741&ref_url=https%253A%252F%252Fwww.mouser.com%252F"
			(at 0 0 0)
			(layer "F.Fab")
			(hide yes)
			(effects
				(font
					(size 1.27 1.27)
					(thickness 0.15)
				)
			)
		)
		(property "Author" "Antmicro"
			(at 0 0 0)
			(layer "F.Fab")
			(hide yes)
			(effects
				(font
					(size 1 1)
					(thickness 0.15)
				)
			)
		)
		(property "License" "Apache-2.0"
			(at 0 0 0)
			(layer "F.Fab")
			(hide yes)
			(effects
				(font
					(size 1 1)
					(thickness 0.15)
				)
			)
		)
		(property "MPN" "TPD4E05U06QDQARQ1"
			(at 0 0 0)
			(layer "F.Fab")
			(hide yes)
			(effects
				(font
					(size 1 1)
					(thickness 0.15)
				)
			)
		)
		(property "Manufacturer" "Texas Instruments"
			(at 0 0 0)
			(layer "F.Fab")
			(hide yes)
			(effects
				(font
					(size 1 1)
					(thickness 0.15)
				)
			)
		)
		(sheetname "/HDMI + SD Card/")
		(sheetfile "hdmi-sd-card.kicad_sch")
		(attr smd)
		(fp_line
			(start 0.498 -1.401)
			(end -0.5 -1.401)
			(stroke
				(width 0.15)
				(type solid)
			)
			(layer "F.SilkS")
		)
		(fp_line
			(start 0.498 1.398)
			(end -0.5 1.398)
			(stroke
				(width 0.15)
				(type solid)
			)
			(layer "F.SilkS")
		)
		(fp_circle
			(center -0.68 -1.27)
			(end -0.63 -1.27)
			(stroke
				(width 0.15)
				(type solid)
			)
			(fill yes)
			(layer "F.SilkS")
		)
		(fp_rect
			(start -0.8 -1.5)
			(end 0.8 1.499)
			(stroke
				(width 0.05)
				(type solid)
			)
			(fill no)
			(layer "F.CrtYd")
		)
		(fp_line
			(start -0.5 -1)
			(end -0.5 1.249)
			(stroke
				(width 0.15)
				(type solid)
			)
			(layer "F.Fab")
		)
		(fp_line
			(start -0.5 1.249)
			(end 0.498 1.249)
			(stroke
				(width 0.15)
				(type solid)
			)
			(layer "F.Fab")
		)
		(fp_line
			(start -0.25 -1.25)
			(end -0.5 -1)
			(stroke
				(width 0.15)
				(type solid)
			)
			(layer "F.Fab")
		)
		(fp_line
			(start 0.498 -1.25)
			(end -0.25 -1.25)
			(stroke
				(width 0.15)
				(type solid)
			)
			(layer "F.Fab")
		)
		(fp_line
			(start 0.498 -1.25)
			(end 0.498 1.249)
			(stroke
				(width 0.15)
				(type solid)
			)
			(layer "F.Fab")
		)
		(pad "1" smd roundrect
			(at -0.387 -1 270)
			(size 0.25 0.55)
			(layers "F.Cu" "F.Mask" "F.Paste")
			(roundrect_rratio 0.25)
			(net 373 "/FPGA bank 16/SD.CLK")
			(pintype "passive")
		)
		(pad "2" smd roundrect
			(at -0.387 -0.5 270)
			(size 0.25 0.55)
			(layers "F.Cu" "F.Mask" "F.Paste")
			(roundrect_rratio 0.25)
			(net 372 "/FPGA bank 16/SD.CMD")
			(pintype "passive")
		)
		(pad "3" smd roundrect
			(at -0.387 0 270)
			(size 0.4 0.55)
			(layers "F.Cu" "F.Mask" "F.Paste")
			(roundrect_rratio 0.25)
			(net 1 "GND")
			(pintype "power_in")
		)
		(pad "4" smd roundrect
			(at -0.387 0.498 270)
			(size 0.25 0.55)
			(layers "F.Cu" "F.Mask" "F.Paste")
			(roundrect_rratio 0.25)
			(net 371 "/FPGA bank 16/SD.DAT3")
			(pintype "passive")
		)
		(pad "5" smd roundrect
			(at -0.387 0.998 270)
			(size 0.25 0.55)
			(layers "F.Cu" "F.Mask" "F.Paste")
			(roundrect_rratio 0.25)
			(net 350 "/FPGA bank 16/SD.DAT2")
			(pintype "passive")
		)
		(pad "6" smd roundrect
			(at 0.385 0.998 270)
			(size 0.25 0.55)
			(layers "F.Cu" "F.Mask" "F.Paste")
			(roundrect_rratio 0.25)
			(net 350 "/FPGA bank 16/SD.DAT2")
			(pintype "passive")
		)
		(pad "7" smd roundrect
			(at 0.385 0.498 270)
			(size 0.25 0.55)
			(layers "F.Cu" "F.Mask" "F.Paste")
			(roundrect_rratio 0.25)
			(net 371 "/FPGA bank 16/SD.DAT3")
			(pintype "passive")
		)
		(pad "8" smd roundrect
			(at 0.385 0 270)
			(size 0.4 0.55)
			(layers "F.Cu" "F.Mask" "F.Paste")
			(roundrect_rratio 0.25)
			(net 1 "GND")
			(pintype "passive")
		)
		(pad "9" smd roundrect
			(at 0.385 -0.5 270)
			(size 0.25 0.55)
			(layers "F.Cu" "F.Mask" "F.Paste")
			(roundrect_rratio 0.25)
			(net 372 "/FPGA bank 16/SD.CMD")
			(pintype "passive")
		)
		(pad "10" smd roundrect
			(at 0.385 -1 270)
			(size 0.25 0.55)
			(layers "F.Cu" "F.Mask" "F.Paste")
			(roundrect_rratio 0.25)
			(net 373 "/FPGA bank 16/SD.CLK")
			(pintype "passive")
		)
	)
	(footprint "antmicro-footprints:Fiducial_1mm_Mask2mm"
		(layer "F.Cu")
		(at 199 114)
		(descr "Circular Fiducial, 1mm bare copper, 3mm soldermask opening")
		(tags "fiducial")
		(property "Reference" "FID1006"
			(at 0 -1.4 0)
			(layer "F.SilkS")
			(hide yes)
			(effects
				(font
					(size 0.7 0.7)
					(thickness 0.15)
				)
				(justify left bottom)
			)
		)
		(property "Value" "Fiducial_1mm_Mask2mm"
			(at 0 2.2 0)
			(layer "F.Fab")
			(effects
				(font
					(size 0.7 0.7)
					(thickness 0.15)
				)
				(justify left bottom)
			)
		)
		(property "Author" "Antmicro"
			(at 0 0 0)
			(layer "F.Fab")
			(hide yes)
			(effects
				(font
					(size 1 1)
					(thickness 0.15)
				)
			)
		)
		(property "License" "Apache-2.0"
			(at 0 0 0)
			(layer "F.Fab")
			(hide yes)
			(effects
				(font
					(size 1 1)
					(thickness 0.15)
				)
			)
		)
		(property "MPN" ""
			(at 0 0 0)
			(layer "F.Fab")
			(hide yes)
			(effects
				(font
					(size 1 1)
					(thickness 0.15)
				)
			)
		)
		(property "Manufacturer" ""
			(at 0 0 0)
			(layer "F.Fab")
			(hide yes)
			(effects
				(font
					(size 1 1)
					(thickness 0.15)
				)
			)
		)
		(sheetfile "sodimm-ddr5-tester.kicad_sch")
		(attr board_only exclude_from_pos_files exclude_from_bom)
		(fp_circle
			(center 0 0)
			(end 1.24 0)
			(stroke
				(width 0.05)
				(type solid)
			)
			(fill no)
			(layer "F.CrtYd")
		)
		(fp_circle
			(center 0 0)
			(end 0.999 0)
			(stroke
				(width 0.15)
				(type solid)
			)
			(fill no)
			(layer "F.Fab")
		)
		(pad "" smd circle
			(at 0 0)
			(size 1 1)
			(layers "F.Cu" "F.Mask")
			(solder_mask_margin 0.5)
			(clearance 0.5)
		)
	)
	(footprint "antmicro-footprints:R_0402_1005Metric"
		(layer "F.Cu")
		(at 177.9 182.415)
		(descr "Resistor SMD 0402")
		(tags "resistor SMD 0402")
		(property "Reference" "R136"
			(at -1.122484 -0.772697 0)
			(layer "F.SilkS")
			(hide yes)
			(effects
				(font
					(size 0.7 0.7)
					(thickness 0.15)
				)
				(justify left bottom)
			)
		)
		(property "Value" "R_0R_0402"
			(at -1.011843 1.772047 0)
			(layer "F.Fab")
			(effects
				(font
					(size 0.7 0.7)
					(thickness 0.15)
				)
				(justify left bottom)
			)
		)
		(property "Datasheet" "https://industrial.panasonic.com/cdbs/www-data/pdf/RDA0000/AOA0000C301.pdf"
			(at 0 0 0)
			(layer "F.Fab")
			(hide yes)
			(effects
				(font
					(size 1.27 1.27)
					(thickness 0.15)
				)
			)
		)
		(property "Author" "Antmicro"
			(at 0 0 0)
			(layer "F.Fab")
			(hide yes)
			(effects
				(font
					(size 1 1)
					(thickness 0.15)
				)
			)
		)
		(property "Current" "1A"
			(at 0 0 0)
			(layer "F.Fab")
			(hide yes)
			(effects
				(font
					(size 1 1)
					(thickness 0.15)
				)
			)
		)
		(property "License" "Apache-2.0"
			(at 0 0 0)
			(layer "F.Fab")
			(hide yes)
			(effects
				(font
					(size 1 1)
					(thickness 0.15)
				)
			)
		)
		(property "MPN" "ERJ2GE0R00X"
			(at 0 0 0)
			(layer "F.Fab")
			(hide yes)
			(effects
				(font
					(size 1 1)
					(thickness 0.15)
				)
			)
		)
		(property "Manufacturer" "Panasonic"
			(at 0 0 0)
			(layer "F.Fab")
			(hide yes)
			(effects
				(font
					(size 1 1)
					(thickness 0.15)
				)
			)
		)
		(property "Tolerance" ""
			(at 0 0 0)
			(layer "F.Fab")
			(hide yes)
			(effects
				(font
					(size 1 1)
					(thickness 0.15)
				)
			)
		)
		(property "Val" "0R"
			(at 0 0 0)
			(layer "F.Fab")
			(hide yes)
			(effects
				(font
					(size 1 1)
					(thickness 0.15)
				)
			)
		)
		(sheetname "/Supply/")
		(sheetfile "supply.kicad_sch")
		(attr smd)
		(fp_rect
			(start -0.93 -0.47)
			(end 0.93 0.47)
			(stroke
				(width 0.05)
				(type solid)
			)
			(fill no)
			(layer "F.CrtYd")
		)
		(fp_rect
			(start -0.5 -0.25)
			(end 0.5 0.25)
			(stroke
				(width 0.15)
				(type solid)
			)
			(fill no)
			(layer "F.Fab")
		)
		(pad "1" smd roundrect
			(at -0.485 0)
			(size 0.59 0.64)
			(layers "F.Cu" "F.Mask" "F.Paste")
			(roundrect_rratio 0.25)
			(net 240 "POWER")
			(pintype "passive")
		)
		(pad "2" smd roundrect
			(at 0.485 0)
			(size 0.59 0.64)
			(layers "F.Cu" "F.Mask" "F.Paste")
			(roundrect_rratio 0.25)
			(net 280 "/Supply/PG1")
			(pintype "passive")
		)
	)
	(footprint "antmicro-footprints:Fiducial_1mm_Mask2mm"
		(layer "F.Cu")
		(at 82.460501 197.866)
		(descr "Circular Fiducial, 1mm bare copper, 3mm soldermask opening")
		(tags "fiducial")
		(property "Reference" "FID1004"
			(at 0 -1.4 0)
			(layer "F.SilkS")
			(hide yes)
			(effects
				(font
					(size 0.7 0.7)
					(thickness 0.15)
				)
				(justify left bottom)
			)
		)
		(property "Value" "Fiducial_1mm_Mask2mm"
			(at 0 2.2 0)
			(layer "F.Fab")
			(effects
				(font
					(size 0.7 0.7)
					(thickness 0.15)
				)
				(justify left bottom)
			)
		)
		(property "Author" "Antmicro"
			(at 0 0 0)
			(layer "F.Fab")
			(hide yes)
			(effects
				(font
					(size 1 1)
					(thickness 0.15)
				)
			)
		)
		(property "License" "Apache-2.0"
			(at 0 0 0)
			(layer "F.Fab")
			(hide yes)
			(effects
				(font
					(size 1 1)
					(thickness 0.15)
				)
			)
		)
		(property "MPN" ""
			(at 0 0 0)
			(layer "F.Fab")
			(hide yes)
			(effects
				(font
					(size 1 1)
					(thickness 0.15)
				)
			)
		)
		(property "Manufacturer" ""
			(at 0 0 0)
			(layer "F.Fab")
			(hide yes)
			(effects
				(font
					(size 1 1)
					(thickness 0.15)
				)
			)
		)
		(sheetfile "sodimm-ddr5-tester.kicad_sch")
		(attr board_only exclude_from_pos_files exclude_from_bom)
		(fp_circle
			(center 0 0)
			(end 1.24 0)
			(stroke
				(width 0.05)
				(type solid)
			)
			(fill no)
			(layer "F.CrtYd")
		)
		(fp_circle
			(center 0 0)
			(end 0.999 0)
			(stroke
				(width 0.15)
				(type solid)
			)
			(fill no)
			(layer "F.Fab")
		)
		(pad "" smd circle
			(at 0 0)
			(size 1 1)
			(layers "F.Cu" "F.Mask")
			(solder_mask_margin 0.5)
			(clearance 0.5)
		)
	)
)
